# TIMECARD (Time Appliance Project (Time Card)) — schematic netlist excerpt (pin names and nets, part order shuffled) for the footprints in the layout excerpt that follows; sources: Cadence DE-HDL packaged netlist, KiCad conversion of R4006-B0001-02_R01.brd

C265  CAPACITOR  0.1UF 25V 10%  pkg SMC_0402R_H022  page 29 : \1\ = UNNAMED_523_CAPACITOR_I24_1 ; \2\ = XP1R0V_SW
C214  CAPACITOR  0.1UF 10V 10%  pkg SMC_0402R_H022  page 14 : \1\ = XP1R0V_FPGA_VCCINT ; \2\ = SG

(kicad_pcb
	(version 20260206)
	(generator "pcbnew")
	(generator_version "10.0")
	(general
		(thickness 1.6)
		(legacy_teardrops no)
	)
	(paper "A4")
	(title_block
		(title "timecard-production-celestica-r4006 — R4006-B0001-02_R01.brd")
		(comment 1 "Time Appliance Project (Time Card) / footprints 767-768 of 1113")
	)
	(layers
		(0 "F.Cu" signal "TOP")
		(4 "In1.Cu" signal "L02_GND1")
		(6 "In2.Cu" signal "L03_SIG1")
		(8 "In3.Cu" signal "L04_GND2")
		(10 "In4.Cu" signal "L05_VCC1")
		(12 "In5.Cu" signal "L06_VCC2")
		(14 "In6.Cu" signal "L07_GND3")
		(16 "In7.Cu" signal "L08_SIG2")
		(18 "In8.Cu" signal "L09_GND4")
		(2 "B.Cu" signal "BOTTOM")
		(9 "F.Adhes" user "F.Adhesive")
		(11 "B.Adhes" user "B.Adhesive")
		(13 "F.Paste" user "Package Geometry/Pastemask Top")
		(15 "B.Paste" user "Package Geometry/Pastemask Bottom")
		(5 "F.SilkS" user "Ref Des/Silkscreen Top")
		(7 "B.SilkS" user "Ref Des/Silkscreen Bottom")
		(1 "F.Mask" user "Board Geometry/Soldermask Top")
		(3 "B.Mask" user "Board Geometry/Soldermask Bottom")
		(17 "Dwgs.User" user "User.Drawings")
		(19 "Cmts.User" user "User.Comments")
		(21 "Eco1.User" user "User.Eco1")
		(23 "Eco2.User" user "User.Eco2")
		(25 "Edge.Cuts" user "Board Geometry/Outline")
		(27 "Margin" user)
		(31 "F.CrtYd" user "Package Geometry/Place Bound Top")
		(29 "B.CrtYd" user "Package Geometry/Place Bound Bottom")
		(35 "F.Fab" user "Ref Des/Assembly Top")
		(33 "B.Fab" user "Ref Des/Assembly Bottom")
	)
	(footprint ""
		(layer "B.Cu")
		(at 139.954 -51.943 90)
		(property "Reference" "C265"
			(at -2.032 -1.18237 270)
			(unlocked yes)
			(layer "B.SilkS")
			(effects
				(font
					(size 0.7874 0.5842)
					(thickness 0.1524)
				)
				(justify mirror)
			)
		)
		(property "Value" "VAL*"
			(at -0.0762 2.067306 90)
			(unlocked yes)
			(layer "B.Fab")
			(hide yes)
			(effects
				(font
					(size 0.7874 0.5842)
					(thickness 0.1524)
				)
				(justify mirror)
			)
		)
		(property "Tolerance" "TOL*"
			(at -0.0762 3.032506 90)
			(unlocked yes)
			(layer "Cmts.User")
			(hide yes)
			(effects
				(font
					(size 0.7874 0.5842)
					(thickness 0.1524)
				)
				(justify mirror)
			)
		)
		(property "User Part Number" "PARTNUM*"
			(at -0.1016 4.023106 90)
			(unlocked yes)
			(layer "Cmts.User")
			(hide yes)
			(effects
				(font
					(size 0.7874 0.5842)
					(thickness 0.1524)
				)
				(justify mirror)
			)
		)
		(property "Device Type" "CAPACITOR-G105-0B104-EK,0.1UF,A"
			(at -0.0508 1.127506 90)
			(unlocked yes)
			(layer "B.Fab")
			(hide yes)
			(effects
				(font
					(size 0.7874 0.5842)
					(thickness 0.1524)
				)
				(justify mirror)
			)
		)
		(duplicate_pad_numbers_are_jumpers no)
		(fp_line
			(start 1.143 -0.5588)
			(end 1.143 0.5588)
			(stroke
				(width 0.1)
				(type default)
			)
			(layer "B.SilkS")
		)
		(fp_line
			(start -1.143 -0.5588)
			(end 1.143 -0.5588)
			(stroke
				(width 0.1)
				(type default)
			)
			(layer "B.SilkS")
		)
		(fp_line
			(start 1.143 0.5588)
			(end -1.143 0.5588)
			(stroke
				(width 0.1)
				(type default)
			)
			(layer "B.SilkS")
		)
		(fp_line
			(start -1.143 0.5588)
			(end -1.143 -0.5588)
			(stroke
				(width 0.1)
				(type default)
			)
			(layer "B.SilkS")
		)
		(fp_rect
			(start 1.143 -0.5588)
			(end -1.143 0.5588)
			(stroke
				(width 0)
				(type default)
			)
			(fill no)
			(layer "B.CrtYd")
		)
		(fp_line
			(start 0.508 -0.3048)
			(end 0.508 0.3048)
			(stroke
				(width 0.1)
				(type default)
			)
			(layer "B.Fab")
		)
		(fp_line
			(start -0.508 -0.3048)
			(end 0.508 -0.3048)
			(stroke
				(width 0.1)
				(type default)
			)
			(layer "B.Fab")
		)
		(fp_line
			(start 0.508 0.3048)
			(end -0.508 0.3048)
			(stroke
				(width 0.1)
				(type default)
			)
			(layer "B.Fab")
		)
		(fp_line
			(start -0.508 0.3048)
			(end -0.508 -0.3048)
			(stroke
				(width 0.1)
				(type default)
			)
			(layer "B.Fab")
		)
		(pad "1" smd rect
			(at 0.5334 0 270)
			(size 0.7112 0.6096)
			(layers "B.Cu" "B.Mask" "B.Paste")
			(net "UNNAMED_523_CAPACITOR_I24_1")
		)
		(pad "2" smd rect
			(at -0.5334 0 270)
			(size 0.7112 0.6096)
			(layers "B.Cu" "B.Mask" "B.Paste")
			(net "XP1R0V_SW")
		)
		(zone
			(layer "B.Cu")
			(hatch none 0.5)
			(connect_pads
				(clearance 0)
			)
			(min_thickness 0.25)
			(keepout
				(tracks allowed)
				(vias not_allowed)
				(pads allowed)
				(copperpour not_allowed)
				(footprints allowed)
			)
			(placement
				(enabled no)
				(sheetname "")
			)
			(fill
				(thermal_gap 0.5)
				(thermal_bridge_width 0.5)
				(island_removal_mode 0)
			)
			(polygon
				(pts
					(xy 139.6492 -52.0192) (xy 139.6492 -51.8668) (xy 140.2588 -51.8668) (xy 140.2588 -52.0192)
				)
			)
		)
	)
	(footprint ""
		(layer "B.Cu")
		(at 110.847124 -39.32301 90)
		(property "Reference" "C214"
			(at -1.14173 -42.016934 270)
			(unlocked yes)
			(layer "B.SilkS")
			(effects
				(font
					(size 0.635 0.4064)
					(thickness 0.1524)
				)
				(justify mirror)
			)
		)
		(property "Value" "VAL*"
			(at 0 3.718306 90)
			(unlocked yes)
			(layer "B.Fab")
			(hide yes)
			(effects
				(font
					(size 0.7874 0.5842)
					(thickness 0.127)
				)
				(justify mirror)
			)
		)
		(property "Tolerance" "TOL*"
			(at 0 4.861306 90)
			(unlocked yes)
			(layer "Cmts.User")
			(hide yes)
			(effects
				(font
					(size 0.7874 0.5842)
					(thickness 0.127)
				)
				(justify mirror)
			)
		)
		(property "User Part Number" "PARTNUM*"
			(at 0 2.575306 90)
			(unlocked yes)
			(layer "Cmts.User")
			(hide yes)
			(effects
				(font
					(size 0.7874 0.5842)
					(thickness 0.127)
				)
				(justify mirror)
			)
		)
		(property "Device Type" "CAPACITOR-G105-0B104-CK,0.1UF,A"
			(at 0 1.432306 90)
			(unlocked yes)
			(layer "B.Fab")
			(hide yes)
			(effects
				(font
					(size 0.7874 0.5842)
					(thickness 0.127)
				)
				(justify mirror)
			)
		)
		(duplicate_pad_numbers_are_jumpers no)
		(fp_line
			(start 0.970026 -0.4699)
			(end -0.970026 -0.4699)
			(stroke
				(width 0.1)
				(type default)
			)
			(layer "B.SilkS")
		)
		(fp_line
			(start -0.970026 -0.4699)
			(end -0.970026 0.4699)
			(stroke
				(width 0.1)
				(type default)
			)
			(layer "B.SilkS")
		)
		(fp_line
			(start 0.970026 0.4699)
			(end 0.970026 -0.4699)
			(stroke
				(width 0.1)
				(type default)
			)
			(layer "B.SilkS")
		)
		(fp_line
			(start -0.970026 0.4699)
			(end 0.970026 0.4699)
			(stroke
				(width 0.1)
				(type default)
			)
			(layer "B.SilkS")
		)
		(fp_poly
			(pts
				(xy 0.970026 0.4699) (xy -0.970026 0.4699) (xy -0.970026 -0.4699) (xy 0.970026 -0.4699)
			)
			(stroke
				(width 0)
				(type default)
			)
			(fill no)
			(layer "B.CrtYd")
		)
		(fp_line
			(start 0.508 -0.3048)
			(end -0.508 -0.3048)
			(stroke
				(width 0.1)
				(type default)
			)
			(layer "B.Fab")
		)
		(fp_line
			(start -0.508 -0.3048)
			(end -0.508 0.3048)
			(stroke
				(width 0.1)
				(type default)
			)
			(layer "B.Fab")
		)
		(fp_line
			(start 0.508 0.3048)
			(end 0.508 -0.3048)
			(stroke
				(width 0.1)
				(type default)
			)
			(layer "B.Fab")
		)
		(fp_line
			(start -0.508 0.3048)
			(end 0.508 0.3048)
			(stroke
				(width 0.1)
				(type default)
			)
			(layer "B.Fab")
		)
		(pad "1" smd circle
			(at 0.500126 0 270)
			(size 0.635 0.635)
			(layers "B.Cu" "B.Mask" "B.Paste")
			(net "XP1R0V_FPGA_VCCINT")
		)
		(pad "2" smd circle
			(at -0.500126 0 270)
			(size 0.635 0.635)
			(layers "B.Cu" "B.Mask" "B.Paste")
			(net "SG")
		)
	)
)
